(kicad_pcb
	(version 20260206)
	(generator "pcbnew")
	(generator_version "10.0")
	(general
		(thickness 1.6)
		(legacy_teardrops no)
	)
	(paper "A4")
	(title_block
		(title "peb — Lightning_PEB_BRD.brd")
		(comment 1 "Lightning (Wiwynn / Facebook NVMe JBOF) / footprints 554-561 of 2563")
	)
	(layers
		(0 "F.Cu" signal "TOP")
		(4 "In1.Cu" signal "L2GND")
		(6 "In2.Cu" signal "L3")
		(8 "In3.Cu" signal "L4VCC")
		(10 "In4.Cu" signal "L5VCC")
		(12 "In5.Cu" signal "L6")
		(14 "In6.Cu" signal "L7GND")
		(2 "B.Cu" signal "BOTTOM")
		(9 "F.Adhes" user "F.Adhesive")
		(11 "B.Adhes" user "B.Adhesive")
		(13 "F.Paste" user "Package Geometry/Pastemask Top")
		(15 "B.Paste" user "Package Geometry/Pastemask Bottom")
		(5 "F.SilkS" user "Ref Des/Silkscreen Top")
		(7 "B.SilkS" user "Ref Des/Silkscreen Bottom")
		(1 "F.Mask" user "Board Geometry/Soldermask Top")
		(3 "B.Mask" user "Board Geometry/Soldermask Bottom")
		(17 "Dwgs.User" user "User.Drawings")
		(19 "Cmts.User" user "User.Comments")
		(21 "Eco1.User" user "User.Eco1")
		(23 "Eco2.User" user "User.Eco2")
		(25 "Edge.Cuts" user "Board Geometry/Outline")
		(27 "Margin" user)
		(31 "F.CrtYd" user "Package Geometry/Place Bound Top")
		(29 "B.CrtYd" user "Package Geometry/Place Bound Bottom")
		(35 "F.Fab" user "Ref Des/Assembly Top")
		(33 "B.Fab" user "Ref Des/Assembly Bottom")
	)
	(footprint ""
		(layer "F.Cu")
		(at 48.641 -148.59 180)
		(property "Reference" "R589"
			(at 0 0 180)
			(layer "F.SilkS")
			(hide yes)
			(effects
				(font
					(size 1.27 1.27)
				)
			)
		)
		(property "Value" "4K7R2F-GP"
			(at 0.064008 -3.993896 180)
			(unlocked yes)
			(layer "F.Fab")
			(hide yes)
			(effects
				(font
					(size 1.016 1.016)
					(thickness 0.1524)
				)
			)
		)
		(property "Device Type" "R402H16"
			(at 0.064008 -5.517896 180)
			(unlocked yes)
			(layer "F.Fab")
			(hide yes)
			(effects
				(font
					(size 1.016 1.016)
					(thickness 0.1524)
				)
			)
		)
		(duplicate_pad_numbers_are_jumpers no)
		(fp_line
			(start 0.508 -0.9398)
			(end -0.508 -0.9398)
			(stroke
				(width 0.1524)
				(type default)
			)
			(layer "F.SilkS")
		)
		(fp_line
			(start -0.508 -0.9398)
			(end -0.508 0.9398)
			(stroke
				(width 0.1524)
				(type default)
			)
			(layer "F.SilkS")
		)
		(fp_rect
			(start -0.508 0.9398)
			(end 0.508 -0.9398)
			(stroke
				(width 0)
				(type default)
			)
			(fill no)
			(layer "F.CrtYd")
		)
		(fp_rect
			(start -0.508 0.9398)
			(end 0.508 -0.9398)
			(stroke
				(width 0)
				(type default)
			)
			(fill no)
			(layer "F.Fab")
		)
		(pad "1" smd custom
			(at 0 -0.4445 180)
			(size 0.1397 0.1397)
			(layers "F.Cu" "F.Mask" "F.Paste")
			(net "P3V3_STBY")
			(options
				(clearance outline)
				(anchor circle)
			)
			(primitives
				(gr_poly
					(pts
						(arc
							(start -0.1778 -0.2794)
							(mid -0.249642 -0.249642)
							(end -0.2794 -0.1778)
						)
						(arc
							(start -0.2794 0.1778)
							(mid -0.249642 0.249642)
							(end -0.1778 0.2794)
						)
						(arc
							(start 0.1778 0.2794)
							(mid 0.249642 0.249642)
							(end 0.2794 0.1778)
						)
						(arc
							(start 0.2794 -0.1778)
							(mid 0.249642 -0.249642)
							(end 0.1778 -0.2794)
						)
					)
					(width 0)
					(fill yes)
				)
			)
		)
		(pad "2" smd custom
			(at 0 0.4445 180)
			(size 0.1397 0.1397)
			(layers "F.Cu" "F.Mask" "F.Paste")
			(net "TEMP_2_A0")
			(options
				(clearance outline)
				(anchor circle)
			)
			(primitives
				(gr_poly
					(pts
						(arc
							(start -0.1778 -0.2794)
							(mid -0.249642 -0.249642)
							(end -0.2794 -0.1778)
						)
						(arc
							(start -0.2794 0.1778)
							(mid -0.249642 0.249642)
							(end -0.1778 0.2794)
						)
						(arc
							(start 0.1778 0.2794)
							(mid 0.249642 0.249642)
							(end 0.2794 0.1778)
						)
						(arc
							(start 0.2794 -0.1778)
							(mid 0.249642 -0.249642)
							(end 0.1778 -0.2794)
						)
					)
					(width 0)
					(fill yes)
				)
			)
		)
	)
	(footprint ""
		(layer "F.Cu")
		(at 62.3062 -154.2796 180)
		(property "Reference" "PG68"
			(at 0 0 180)
			(layer "F.SilkS")
			(hide yes)
			(effects
				(font
					(size 1.27 1.27)
				)
			)
		)
		(property "Value" "GAP-CLOSE-PWR-3-GP"
			(at 0.0254 -6.5786 180)
			(unlocked yes)
			(layer "F.Fab")
			(hide yes)
			(effects
				(font
					(size 1.016 1.016)
					(thickness 0.1524)
				)
			)
		)
		(property "Device Type" "GAP-CLOSE-PWR-3"
			(at 0.0254 -8.255 180)
			(unlocked yes)
			(layer "F.Fab")
			(hide yes)
			(effects
				(font
					(size 1.016 1.016)
					(thickness 0.1524)
				)
			)
		)
		(duplicate_pad_numbers_are_jumpers no)
		(fp_rect
			(start -0.7112 0.4572)
			(end 0.7112 -0.4572)
			(stroke
				(width 0)
				(type default)
			)
			(fill no)
			(layer "F.CrtYd")
		)
		(fp_poly
			(pts
				(xy -0.7112 -0.4572) (xy 0.7112 -0.4572) (xy 0.7112 0.4572) (xy -0.7112 0.4572)
			)
			(stroke
				(width 0)
				(type default)
			)
			(fill no)
			(layer "F.Fab")
		)
		(pad "1" smd rect
			(at -0.3048 0 180)
			(size 0.6604 0.762)
			(layers "F.Cu" "F.Mask" "F.Paste")
			(net "P1V53_PWR")
		)
		(pad "2" smd rect
			(at 0.3048 0 180)
			(size 0.6604 0.762)
			(layers "F.Cu" "F.Mask" "F.Paste")
			(net "P1V53_STBY")
		)
	)
	(footprint ""
		(layer "F.Cu")
		(at 219.329 -8.128 -90)
		(property "Reference" "R660"
			(at 0 0 270)
			(layer "F.SilkS")
			(hide yes)
			(effects
				(font
					(size 1.27 1.27)
				)
			)
		)
		(property "Value" "100KR2F-L1-GP"
			(at 0.064008 -3.993896 270)
			(unlocked yes)
			(layer "F.Fab")
			(hide yes)
			(effects
				(font
					(size 1.016 1.016)
					(thickness 0.1524)
				)
			)
		)
		(property "Device Type" "R402H16"
			(at 0.064008 -5.517896 270)
			(unlocked yes)
			(layer "F.Fab")
			(hide yes)
			(effects
				(font
					(size 1.016 1.016)
					(thickness 0.1524)
				)
			)
		)
		(duplicate_pad_numbers_are_jumpers no)
		(fp_line
			(start -0.508 -0.9398)
			(end -0.508 0.9398)
			(stroke
				(width 0.1524)
				(type default)
			)
			(layer "F.SilkS")
		)
		(fp_line
			(start 0.508 -0.9398)
			(end -0.508 -0.9398)
			(stroke
				(width 0.1524)
				(type default)
			)
			(layer "F.SilkS")
		)
		(fp_rect
			(start -0.508 0.9398)
			(end 0.508 -0.9398)
			(stroke
				(width 0)
				(type default)
			)
			(fill no)
			(layer "F.CrtYd")
		)
		(fp_rect
			(start -0.508 0.9398)
			(end 0.508 -0.9398)
			(stroke
				(width 0)
				(type default)
			)
			(fill no)
			(layer "F.Fab")
		)
		(pad "1" smd custom
			(at 0 -0.4445 270)
			(size 0.1397 0.1397)
			(layers "F.Cu" "F.Mask" "F.Paste")
			(net "EEPROM_A2")
			(options
				(clearance outline)
				(anchor circle)
			)
			(primitives
				(gr_poly
					(pts
						(arc
							(start -0.1778 -0.2794)
							(mid -0.249642 -0.249642)
							(end -0.2794 -0.1778)
						)
						(arc
							(start -0.2794 0.1778)
							(mid -0.249642 0.249642)
							(end -0.1778 0.2794)
						)
						(arc
							(start 0.1778 0.2794)
							(mid 0.249642 0.249642)
							(end 0.2794 0.1778)
						)
						(arc
							(start 0.2794 -0.1778)
							(mid 0.249642 -0.249642)
							(end 0.1778 -0.2794)
						)
					)
					(width 0)
					(fill yes)
				)
			)
		)
		(pad "2" smd custom
			(at 0 0.4445 270)
			(size 0.1397 0.1397)
			(layers "F.Cu" "F.Mask" "F.Paste")
			(net "GND")
			(options
				(clearance outline)
				(anchor circle)
			)
			(primitives
				(gr_poly
					(pts
						(arc
							(start -0.1778 -0.2794)
							(mid -0.249642 -0.249642)
							(end -0.2794 -0.1778)
						)
						(arc
							(start -0.2794 0.1778)
							(mid -0.249642 0.249642)
							(end -0.1778 0.2794)
						)
						(arc
							(start 0.1778 0.2794)
							(mid 0.249642 0.249642)
							(end 0.2794 0.1778)
						)
						(arc
							(start 0.2794 -0.1778)
							(mid 0.249642 -0.249642)
							(end 0.1778 -0.2794)
						)
					)
					(width 0)
					(fill yes)
				)
			)
		)
	)
	(footprint ""
		(layer "F.Cu")
		(at 145.8214 -60.5536 -90)
		(property "Reference" "PR175"
			(at 0 0 270)
			(layer "F.SilkS")
			(hide yes)
			(effects
				(font
					(size 1.27 1.27)
				)
			)
		)
		(property "Value" "100KR2F-L1-GP"
			(at 0.064008 -3.993896 270)
			(unlocked yes)
			(layer "F.Fab")
			(hide yes)
			(effects
				(font
					(size 1.016 1.016)
					(thickness 0.1524)
				)
			)
		)
		(property "Device Type" "R402H16"
			(at 0.064008 -5.517896 270)
			(unlocked yes)
			(layer "F.Fab")
			(hide yes)
			(effects
				(font
					(size 1.016 1.016)
					(thickness 0.1524)
				)
			)
		)
		(duplicate_pad_numbers_are_jumpers no)
		(fp_line
			(start -0.508 -0.9398)
			(end -0.508 0.9398)
			(stroke
				(width 0.1524)
				(type default)
			)
			(layer "F.SilkS")
		)
		(fp_line
			(start 0.508 -0.9398)
			(end -0.508 -0.9398)
			(stroke
				(width 0.1524)
				(type default)
			)
			(layer "F.SilkS")
		)
		(fp_rect
			(start -0.508 0.9398)
			(end 0.508 -0.9398)
			(stroke
				(width 0)
				(type default)
			)
			(fill no)
			(layer "F.CrtYd")
		)
		(fp_rect
			(start -0.508 0.9398)
			(end 0.508 -0.9398)
			(stroke
				(width 0)
				(type default)
			)
			(fill no)
			(layer "F.Fab")
		)
		(pad "1" smd custom
			(at 0 -0.4445 270)
			(size 0.1397 0.1397)
			(layers "F.Cu" "F.Mask" "F.Paste")
			(net "P0V9_VREG")
			(options
				(clearance outline)
				(anchor circle)
			)
			(primitives
				(gr_poly
					(pts
						(arc
							(start -0.1778 -0.2794)
							(mid -0.249642 -0.249642)
							(end -0.2794 -0.1778)
						)
						(arc
							(start -0.2794 0.1778)
							(mid -0.249642 0.249642)
							(end -0.1778 0.2794)
						)
						(arc
							(start 0.1778 0.2794)
							(mid 0.249642 0.249642)
							(end 0.2794 0.1778)
						)
						(arc
							(start 0.2794 -0.1778)
							(mid 0.249642 -0.249642)
							(end 0.1778 -0.2794)
						)
					)
					(width 0)
					(fill yes)
				)
			)
		)
		(pad "2" smd custom
			(at 0 0.4445 270)
			(size 0.1397 0.1397)
			(layers "F.Cu" "F.Mask" "F.Paste")
			(net "P0V9_RF")
			(options
				(clearance outline)
				(anchor circle)
			)
			(primitives
				(gr_poly
					(pts
						(arc
							(start -0.1778 -0.2794)
							(mid -0.249642 -0.249642)
							(end -0.2794 -0.1778)
						)
						(arc
							(start -0.2794 0.1778)
							(mid -0.249642 0.249642)
							(end -0.1778 0.2794)
						)
						(arc
							(start 0.1778 0.2794)
							(mid 0.249642 0.249642)
							(end 0.2794 0.1778)
						)
						(arc
							(start 0.2794 -0.1778)
							(mid 0.249642 -0.249642)
							(end 0.1778 -0.2794)
						)
					)
					(width 0)
					(fill yes)
				)
			)
		)
	)
	(footprint ""
		(layer "F.Cu")
		(at 181.61 -19.812 -90)
		(property "Reference" "C410"
			(at 0 0 270)
			(layer "F.SilkS")
			(hide yes)
			(effects
				(font
					(size 1.27 1.27)
				)
			)
		)
		(property "Value" "SCD22U10V2KX-1GP"
			(at 1.1811 -2.7051 270)
			(unlocked yes)
			(layer "F.Fab")
			(hide yes)
			(effects
				(font
					(size 1.016 1.016)
					(thickness 0.1524)
				)
			)
		)
		(property "Device Type" "C402H22"
			(at 1.1811 -4.2291 270)
			(unlocked yes)
			(layer "F.Fab")
			(hide yes)
			(effects
				(font
					(size 1.016 1.016)
					(thickness 0.1524)
				)
			)
		)
		(duplicate_pad_numbers_are_jumpers no)
		(fp_rect
			(start -0.4318 0.9525)
			(end 0.4318 -0.9525)
			(stroke
				(width 0)
				(type default)
			)
			(fill no)
			(layer "F.CrtYd")
		)
		(fp_rect
			(start -0.4318 0.9525)
			(end 0.4318 -0.9525)
			(stroke
				(width 0)
				(type default)
			)
			(fill no)
			(layer "F.Fab")
		)
		(pad "1" smd custom
			(at 0 -0.4445 270)
			(size 0.1524 0.1524)
			(layers "F.Cu" "F.Mask" "F.Paste")
			(net "PCIE_TX_CAP_N95")
			(options
				(clearance outline)
				(anchor circle)
			)
			(primitives
				(gr_poly
					(pts
						(arc
							(start 0.3048 -0.2032)
							(mid 0.275042 -0.275042)
							(end 0.2032 -0.3048)
						)
						(arc
							(start -0.2032 -0.3048)
							(mid -0.275042 -0.275042)
							(end -0.3048 -0.2032)
						)
						(arc
							(start -0.3048 0.2032)
							(mid -0.275042 0.275042)
							(end -0.2032 0.3048)
						)
						(arc
							(start 0.2032 0.3048)
							(mid 0.275042 0.275042)
							(end 0.3048 0.2032)
						)
					)
					(width 0)
					(fill yes)
				)
			)
		)
		(pad "2" smd custom
			(at 0 0.4445 270)
			(size 0.1524 0.1524)
			(layers "F.Cu" "F.Mask" "F.Paste")
			(net "PCIE_TX_N95")
			(options
				(clearance outline)
				(anchor circle)
			)
			(primitives
				(gr_poly
					(pts
						(arc
							(start 0.3048 -0.2032)
							(mid 0.275042 -0.275042)
							(end 0.2032 -0.3048)
						)
						(arc
							(start -0.2032 -0.3048)
							(mid -0.275042 -0.275042)
							(end -0.3048 -0.2032)
						)
						(arc
							(start -0.3048 0.2032)
							(mid -0.275042 0.275042)
							(end -0.2032 0.3048)
						)
						(arc
							(start 0.2032 0.3048)
							(mid 0.275042 0.275042)
							(end 0.3048 0.2032)
						)
					)
					(width 0)
					(fill yes)
				)
			)
		)
	)
	(footprint ""
		(layer "F.Cu")
		(at 211.900008 -4.064)
		(property "Reference" "R678"
			(at 0 0 0)
			(layer "F.SilkS")
			(hide yes)
			(effects
				(font
					(size 1.27 1.27)
				)
			)
		)
		(property "Value" "100KR2F-L1-GP"
			(at 0.064008 -3.993896 0)
			(unlocked yes)
			(layer "F.Fab")
			(hide yes)
			(effects
				(font
					(size 1.016 1.016)
					(thickness 0.1524)
				)
			)
		)
		(property "Device Type" "R402H16"
			(at 0.064008 -5.517896 0)
			(unlocked yes)
			(layer "F.Fab")
			(hide yes)
			(effects
				(font
					(size 1.016 1.016)
					(thickness 0.1524)
				)
			)
		)
		(duplicate_pad_numbers_are_jumpers no)
		(fp_line
			(start -0.508 -0.9398)
			(end -0.508 0.9398)
			(stroke
				(width 0.1524)
				(type default)
			)
			(layer "F.SilkS")
		)
		(fp_line
			(start 0.508 -0.9398)
			(end -0.508 -0.9398)
			(stroke
				(width 0.1524)
				(type default)
			)
			(layer "F.SilkS")
		)
		(fp_rect
			(start -0.508 0.9398)
			(end 0.508 -0.9398)
			(stroke
				(width 0)
				(type default)
			)
			(fill no)
			(layer "F.CrtYd")
		)
		(fp_rect
			(start -0.508 0.9398)
			(end 0.508 -0.9398)
			(stroke
				(width 0)
				(type default)
			)
			(fill no)
			(layer "F.Fab")
		)
		(pad "1" smd custom
			(at 0 -0.4445)
			(size 0.1397 0.1397)
			(layers "F.Cu" "F.Mask" "F.Paste")
			(net "HOST5_RST_N")
			(options
				(clearance outline)
				(anchor circle)
			)
			(primitives
				(gr_poly
					(pts
						(arc
							(start -0.1778 -0.2794)
							(mid -0.249642 -0.249642)
							(end -0.2794 -0.1778)
						)
						(arc
							(start -0.2794 0.1778)
							(mid -0.249642 0.249642)
							(end -0.1778 0.2794)
						)
						(arc
							(start 0.1778 0.2794)
							(mid 0.249642 0.249642)
							(end 0.2794 0.1778)
						)
						(arc
							(start 0.2794 -0.1778)
							(mid 0.249642 -0.249642)
							(end 0.1778 -0.2794)
						)
					)
					(width 0)
					(fill yes)
				)
			)
		)
		(pad "2" smd custom
			(at 0 0.4445)
			(size 0.1397 0.1397)
			(layers "F.Cu" "F.Mask" "F.Paste")
			(net "GND")
			(options
				(clearance outline)
				(anchor circle)
			)
			(primitives
				(gr_poly
					(pts
						(arc
							(start -0.1778 -0.2794)
							(mid -0.249642 -0.249642)
							(end -0.2794 -0.1778)
						)
						(arc
							(start -0.2794 0.1778)
							(mid -0.249642 0.249642)
							(end -0.1778 0.2794)
						)
						(arc
							(start 0.1778 0.2794)
							(mid 0.249642 0.249642)
							(end 0.2794 0.1778)
						)
						(arc
							(start 0.2794 -0.1778)
							(mid 0.249642 -0.249642)
							(end 0.1778 -0.2794)
						)
					)
					(width 0)
					(fill yes)
				)
			)
		)
	)
	(footprint ""
		(layer "F.Cu")
		(at 22.61362 -69.5452 90)
		(property "Reference" "C631"
			(at 0 0 90)
			(layer "F.SilkS")
			(hide yes)
			(effects
				(font
					(size 1.27 1.27)
				)
			)
		)
		(property "Value" "SCD1U16V2KX-3GP"
			(at 1.1811 -2.7051 90)
			(unlocked yes)
			(layer "F.Fab")
			(hide yes)
			(effects
				(font
					(size 1.016 1.016)
					(thickness 0.1524)
				)
			)
		)
		(property "Device Type" "C402H22"
			(at 1.1811 -4.2291 90)
			(unlocked yes)
			(layer "F.Fab")
			(hide yes)
			(effects
				(font
					(size 1.016 1.016)
					(thickness 0.1524)
				)
			)
		)
		(duplicate_pad_numbers_are_jumpers no)
		(fp_rect
			(start -0.4318 0.9525)
			(end 0.4318 -0.9525)
			(stroke
				(width 0)
				(type default)
			)
			(fill no)
			(layer "F.CrtYd")
		)
		(fp_rect
			(start -0.4318 0.9525)
			(end 0.4318 -0.9525)
			(stroke
				(width 0)
				(type default)
			)
			(fill no)
			(layer "F.Fab")
		)
		(pad "1" smd custom
			(at 0 -0.4445 90)
			(size 0.1524 0.1524)
			(layers "F.Cu" "F.Mask" "F.Paste")
			(net "P3V3_STBY")
			(options
				(clearance outline)
				(anchor circle)
			)
			(primitives
				(gr_poly
					(pts
						(arc
							(start 0.3048 -0.2032)
							(mid 0.275042 -0.275042)
							(end 0.2032 -0.3048)
						)
						(arc
							(start -0.2032 -0.3048)
							(mid -0.275042 -0.275042)
							(end -0.3048 -0.2032)
						)
						(arc
							(start -0.3048 0.2032)
							(mid -0.275042 0.275042)
							(end -0.2032 0.3048)
						)
						(arc
							(start 0.2032 0.3048)
							(mid 0.275042 0.275042)
							(end 0.3048 0.2032)
						)
					)
					(width 0)
					(fill yes)
				)
			)
		)
		(pad "2" smd custom
			(at 0 0.4445 90)
			(size 0.1524 0.1524)
			(layers "F.Cu" "F.Mask" "F.Paste")
			(net "GND")
			(options
				(clearance outline)
				(anchor circle)
			)
			(primitives
				(gr_poly
					(pts
						(arc
							(start 0.3048 -0.2032)
							(mid 0.275042 -0.275042)
							(end 0.2032 -0.3048)
						)
						(arc
							(start -0.2032 -0.3048)
							(mid -0.275042 -0.275042)
							(end -0.3048 -0.2032)
						)
						(arc
							(start -0.3048 0.2032)
							(mid -0.275042 0.275042)
							(end -0.2032 0.3048)
						)
						(arc
							(start 0.2032 0.3048)
							(mid 0.275042 0.275042)
							(end 0.3048 0.2032)
						)
					)
					(width 0)
					(fill yes)
				)
			)
		)
	)
	(footprint ""
		(layer "F.Cu")
		(at 265.408156 -212.420454 180)
		(property "Reference" "C106"
			(at 0 0 180)
			(layer "F.SilkS")
			(hide yes)
			(effects
				(font
					(size 1.27 1.27)
				)
			)
		)
		(property "Value" "SCD22U10V2KX-1GP"
			(at 1.1811 -2.7051 180)
			(unlocked yes)
			(layer "F.Fab")
			(hide yes)
			(effects
				(font
					(size 1.016 1.016)
					(thickness 0.1524)
				)
			)
		)
		(property "Device Type" "C402H22"
			(at 1.1811 -4.2291 180)
			(unlocked yes)
			(layer "F.Fab")
			(hide yes)
			(effects
				(font
					(size 1.016 1.016)
					(thickness 0.1524)
				)
			)
		)
		(duplicate_pad_numbers_are_jumpers no)
		(fp_rect
			(start -0.4318 0.9525)
			(end 0.4318 -0.9525)
			(stroke
				(width 0)
				(type default)
			)
			(fill no)
			(layer "F.CrtYd")
		)
		(fp_rect
			(start -0.4318 0.9525)
			(end 0.4318 -0.9525)
			(stroke
				(width 0)
				(type default)
			)
			(fill no)
			(layer "F.Fab")
		)
		(pad "1" smd custom
			(at 0 -0.4445 180)
			(size 0.1524 0.1524)
			(layers "F.Cu" "F.Mask" "F.Paste")
			(net "PCIE_TX_CAP_N37")
			(options
				(clearance outline)
				(anchor circle)
			)
			(primitives
				(gr_poly
					(pts
						(arc
							(start 0.3048 -0.2032)
							(mid 0.275042 -0.275042)
							(end 0.2032 -0.3048)
						)
						(arc
							(start -0.2032 -0.3048)
							(mid -0.275042 -0.275042)
							(end -0.3048 -0.2032)
						)
						(arc
							(start -0.3048 0.2032)
							(mid -0.275042 0.275042)
							(end -0.2032 0.3048)
						)
						(arc
							(start 0.2032 0.3048)
							(mid 0.275042 0.275042)
							(end 0.3048 0.2032)
						)
					)
					(width 0)
					(fill yes)
				)
			)
		)
		(pad "2" smd custom
			(at 0 0.4445 180)
			(size 0.1524 0.1524)
			(layers "F.Cu" "F.Mask" "F.Paste")
			(net "PCIE_TX_N37")
			(options
				(clearance outline)
				(anchor circle)
			)
			(primitives
				(gr_poly
					(pts
						(arc
							(start 0.3048 -0.2032)
							(mid 0.275042 -0.275042)
							(end 0.2032 -0.3048)
						)
						(arc
							(start -0.2032 -0.3048)
							(mid -0.275042 -0.275042)
							(end -0.3048 -0.2032)
						)
						(arc
							(start -0.3048 0.2032)
							(mid -0.275042 0.275042)
							(end -0.2032 0.3048)
						)
						(arc
							(start 0.2032 0.3048)
							(mid 0.275042 0.275042)
							(end 0.3048 0.2032)
						)
					)
					(width 0)
					(fill yes)
				)
			)
		)
	)
)
